# T6G (Grand Teton) — schematic netlist excerpt (pin names and nets, part order shuffled) for the footprints in the layout excerpt that follows; sources: Cadence DE-HDL packaged netlist, KiCad conversion of 04192023_DAF0TMB3IC0_F0TG_MB_C_brd_V02_OCP.brd

R346  Q_RES  49.9 1% EMPTY  pkg 0201LF  page 180 : A = USB3_CPU0_BMC_TX_C2_DN ; B = GND
R1086  Q_RES  0 5% EMPTY  pkg 0402LF  page 312 : A = P1V8_CPU0_RT3_1A_1D ; B = P1V8_CPU0_RT3_1A

U147  SN74AVC2T245RSWR  IC  pkg UQFN10_0-4_1-8X1-4  page 172
  DIR2  = GND
  \oe_#\  = JTAG_BMC_OE_N
  GND  = GND
  B2  = JTAG_TDO_R1
  B1  = JTAG_TDI_R
  VCCB  = PVDD18_S5_P0
  VCCA  = P3V3_AUX
  A1  = JTAG_SCM_MUX_TDO
  A2  = JTAG_SCM_MUX_TDI
  DIR1  = P3V3_AUX

(kicad_pcb
	(version 20260206)
	(generator "pcbnew")
	(generator_version "10.0")
	(general
		(thickness 1.6)
		(legacy_teardrops no)
	)
	(paper "A4")
	(title_block
		(title "04192023_DAF0TMB3IC0_F0TG_MB_C_brd_V02_OCP.brd")
		(comment 1 "Grand Teton / footprints 2389-2391 of 8354")
	)
	(layers
		(0 "F.Cu" signal "TOP")
		(4 "In1.Cu" signal "GND")
		(6 "In2.Cu" signal "IN1")
		(8 "In3.Cu" signal "GND1")
		(10 "In4.Cu" signal "IN2")
		(12 "In5.Cu" signal "GND2")
		(14 "In6.Cu" signal "IN3")
		(16 "In7.Cu" signal "GND3")
		(18 "In8.Cu" signal "VCC")
		(20 "In9.Cu" signal "VCC1")
		(22 "In10.Cu" signal "GND4")
		(24 "In11.Cu" signal "IN4")
		(26 "In12.Cu" signal "GND5")
		(28 "In13.Cu" signal "IN5")
		(30 "In14.Cu" signal "GND6")
		(32 "In15.Cu" signal "IN6")
		(34 "In16.Cu" signal "GND7")
		(2 "B.Cu" signal "BOTTOM")
		(9 "F.Adhes" user "F.Adhesive")
		(11 "B.Adhes" user "B.Adhesive")
		(13 "F.Paste" user "Package Geometry/Pastemask Top")
		(15 "B.Paste" user "Package Geometry/Pastemask Bottom")
		(5 "F.SilkS" user "Ref Des/Silkscreen Top")
		(7 "B.SilkS" user "Ref Des/Silkscreen Bottom")
		(1 "F.Mask" user "Board Geometry/Soldermask Top")
		(3 "B.Mask" user "Board Geometry/Soldermask Bottom")
		(17 "Dwgs.User" user "User.Drawings")
		(19 "Cmts.User" user "User.Comments")
		(21 "Eco1.User" user "User.Eco1")
		(23 "Eco2.User" user "User.Eco2")
		(25 "Edge.Cuts" user "Board Geometry/Outline")
		(27 "Margin" user)
		(31 "F.CrtYd" user "Package Geometry/Place Bound Top")
		(29 "B.CrtYd" user "Package Geometry/Place Bound Bottom")
		(35 "F.Fab" user "Ref Des/Assembly Top")
		(33 "B.Fab" user "Ref Des/Assembly Bottom")
	)
	(footprint ""
		(layer "F.Cu")
		(at 146.27479 -57.275984 -90)
		(property "Reference" "U147"
			(at 1.504188 2.769108 90)
			(unlocked yes)
			(layer "F.SilkS")
			(effects
				(font
					(size 0.7874 0.5842)
					(thickness 0.1524)
				)
				(justify left)
			)
		)
		(property "Value" ""
			(at 0 0 270)
			(layer "F.Fab")
			(effects
				(font
					(size 1.27 1.27)
				)
			)
		)
		(duplicate_pad_numbers_are_jumpers no)
		(fp_line
			(start -1.245616 1.445768)
			(end -1.245616 -1.445768)
			(stroke
				(width 0.1524)
				(type default)
			)
			(layer "F.SilkS")
		)
		(fp_line
			(start 1.245616 1.445768)
			(end -1.245616 1.445768)
			(stroke
				(width 0.1524)
				(type default)
			)
			(layer "F.SilkS")
		)
		(fp_line
			(start -1.245616 -1.445768)
			(end 1.245616 -1.445768)
			(stroke
				(width 0.1524)
				(type default)
			)
			(layer "F.SilkS")
		)
		(fp_line
			(start 1.245616 -1.445768)
			(end 1.245616 1.445768)
			(stroke
				(width 0.1524)
				(type default)
			)
			(layer "F.SilkS")
		)
		(fp_poly
			(pts
				(xy -1.386586 -0.199898) (xy -1.894586 0.054102) (xy -1.894586 -0.453898)
			)
			(stroke
				(width 0)
				(type default)
			)
			(fill yes)
			(layer "F.SilkS")
		)
		(fp_line
			(start -0.724916 0.925068)
			(end -0.724916 -0.925068)
			(stroke
				(width 0.1)
				(type default)
			)
			(layer "F.Fab")
		)
		(fp_line
			(start 0.724916 0.925068)
			(end -0.724916 0.925068)
			(stroke
				(width 0.1)
				(type default)
			)
			(layer "F.Fab")
		)
		(fp_line
			(start -0.724916 -0.925068)
			(end 0.724916 -0.925068)
			(stroke
				(width 0.1)
				(type default)
			)
			(layer "F.Fab")
		)
		(fp_line
			(start 0.724916 -0.925068)
			(end 0.724916 0.925068)
			(stroke
				(width 0.1)
				(type default)
			)
			(layer "F.Fab")
		)
		(fp_poly
			(pts
				(xy -1.894586 -0.453898) (xy -1.894586 0.054102) (xy -1.386586 -0.199898)
			)
			(stroke
				(width 0)
				(type default)
			)
			(fill yes)
			(layer "F.Fab")
		)
		(pad "1" smd circle
			(at -0.649986 -0.199898 180)
			(size 0 0)
			(layers "F.Cu" "F.Mask" "F.Paste")
			(net "GND")
		)
		(pad "2" smd rect
			(at -0.700024 0.199898)
			(size 0.1778 0.8128)
			(layers "F.Cu" "F.Mask" "F.Paste")
			(net "JTAG_BMC_OE_N")
		)
		(pad "3" smd rect
			(at -0.40005 0.899922 270)
			(size 0.1778 0.8128)
			(layers "F.Cu" "F.Mask" "F.Paste")
			(net "GND")
		)
		(pad "4" smd rect
			(at 0 0.899922 270)
			(size 0.1778 0.8128)
			(layers "F.Cu" "F.Mask" "F.Paste")
			(net "JTAG_TDO_R1")
		)
		(pad "5" smd rect
			(at 0.40005 0.899922 270)
			(size 0.1778 0.8128)
			(layers "F.Cu" "F.Mask" "F.Paste")
			(net "JTAG_TDI_R")
		)
		(pad "6" smd rect
			(at 0.700024 0.199898 180)
			(size 0.1778 0.8128)
			(layers "F.Cu" "F.Mask" "F.Paste")
			(net "PVDD18_S5_P0")
		)
		(pad "7" smd rect
			(at 0.700024 -0.199898 180)
			(size 0.1778 0.8128)
			(layers "F.Cu" "F.Mask" "F.Paste")
			(net "P3V3_AUX")
		)
		(pad "8" smd rect
			(at 0.40005 -0.899922 270)
			(size 0.1778 0.8128)
			(layers "F.Cu" "F.Mask" "F.Paste")
			(net "JTAG_SCM_MUX_TDO")
		)
		(pad "9" smd rect
			(at 0 -0.899922 270)
			(size 0.1778 0.8128)
			(layers "F.Cu" "F.Mask" "F.Paste")
			(net "JTAG_SCM_MUX_TDI")
		)
		(pad "10" smd rect
			(at -0.40005 -0.912622 270)
			(size 0.1778 0.7874)
			(layers "F.Cu" "F.Mask" "F.Paste")
			(net "P3V3_AUX")
		)
	)
	(footprint ""
		(layer "F.Cu")
		(at 392.962384 -392.48588 180)
		(property "Reference" "R1086"
			(at 0 0 180)
			(layer "F.SilkS")
			(hide yes)
			(effects
				(font
					(size 1.27 1.27)
				)
			)
		)
		(property "Value" ""
			(at 0 0 180)
			(layer "F.Fab")
			(effects
				(font
					(size 1.27 1.27)
				)
			)
		)
		(duplicate_pad_numbers_are_jumpers no)
		(fp_line
			(start 0.7874 0.4064)
			(end -0.7874 0.4064)
			(stroke
				(width 0.1524)
				(type default)
			)
			(layer "F.SilkS")
		)
		(fp_line
			(start 0.7874 -0.4064)
			(end 0.7874 0.4064)
			(stroke
				(width 0.1524)
				(type default)
			)
			(layer "F.SilkS")
		)
		(fp_line
			(start -0.7874 0.4064)
			(end -0.7874 -0.4064)
			(stroke
				(width 0.1524)
				(type default)
			)
			(layer "F.SilkS")
		)
		(fp_line
			(start -0.7874 -0.4064)
			(end 0.7874 -0.4064)
			(stroke
				(width 0.1524)
				(type default)
			)
			(layer "F.SilkS")
		)
		(fp_line
			(start 0.67945 0.3048)
			(end 0.120396 0.3048)
			(stroke
				(width 0.1)
				(type default)
			)
			(layer "F.Fab")
		)
		(fp_line
			(start 0.67945 -0.3048)
			(end 0.67945 0.3048)
			(stroke
				(width 0.1)
				(type default)
			)
			(layer "F.Fab")
		)
		(fp_line
			(start 0.12065 -0.2794)
			(end 0.12065 -0.3048)
			(stroke
				(width 0.1)
				(type default)
			)
			(layer "F.Fab")
		)
		(fp_line
			(start 0.12065 -0.3048)
			(end 0.67945 -0.3048)
			(stroke
				(width 0.1)
				(type default)
			)
			(layer "F.Fab")
		)
		(fp_line
			(start 0.120396 0.3048)
			(end 0.120396 0.2794)
			(stroke
				(width 0.1)
				(type default)
			)
			(layer "F.Fab")
		)
		(fp_line
			(start 0.120396 0.2794)
			(end -0.12065 0.2794)
			(stroke
				(width 0.1)
				(type default)
			)
			(layer "F.Fab")
		)
		(fp_line
			(start -0.12065 0.3048)
			(end -0.67945 0.3048)
			(stroke
				(width 0.1)
				(type default)
			)
			(layer "F.Fab")
		)
		(fp_line
			(start -0.12065 0.2794)
			(end -0.12065 0.3048)
			(stroke
				(width 0.1)
				(type default)
			)
			(layer "F.Fab")
		)
		(fp_line
			(start -0.12065 -0.2794)
			(end 0.12065 -0.2794)
			(stroke
				(width 0.1)
				(type default)
			)
			(layer "F.Fab")
		)
		(fp_line
			(start -0.12065 -0.305054)
			(end -0.12065 -0.2794)
			(stroke
				(width 0.1)
				(type default)
			)
			(layer "F.Fab")
		)
		(fp_line
			(start -0.67945 0.3048)
			(end -0.67945 -0.305054)
			(stroke
				(width 0.1)
				(type default)
			)
			(layer "F.Fab")
		)
		(fp_line
			(start -0.67945 -0.305054)
			(end -0.12065 -0.305054)
			(stroke
				(width 0.1)
				(type default)
			)
			(layer "F.Fab")
		)
		(pad "1" smd rect
			(at -0.40005 0)
			(size 0.4572 0.508)
			(layers "F.Cu" "F.Mask" "F.Paste")
			(net "P1V8_CPU0_RT3_1A_1D")
		)
		(pad "2" smd rect
			(at 0.40005 0)
			(size 0.4572 0.508)
			(layers "F.Cu" "F.Mask" "F.Paste")
			(net "P1V8_CPU0_RT3_1A")
		)
	)
	(footprint ""
		(layer "F.Cu")
		(at 103.185722 -28.422854 -90)
		(property "Reference" "R346"
			(at 0 0 270)
			(layer "F.SilkS")
			(hide yes)
			(effects
				(font
					(size 1.27 1.27)
				)
			)
		)
		(property "Value" ""
			(at 0 0 270)
			(layer "F.Fab")
			(effects
				(font
					(size 1.27 1.27)
				)
			)
		)
		(duplicate_pad_numbers_are_jumpers no)
		(fp_line
			(start -0.32512 0.175006)
			(end -0.32512 -0.175006)
			(stroke
				(width 0.1)
				(type default)
			)
			(layer "F.Fab")
		)
		(fp_line
			(start 0.32512 0.175006)
			(end -0.32512 0.175006)
			(stroke
				(width 0.1)
				(type default)
			)
			(layer "F.Fab")
		)
		(fp_line
			(start -0.32512 -0.175006)
			(end 0.32512 -0.175006)
			(stroke
				(width 0.1)
				(type default)
			)
			(layer "F.Fab")
		)
		(fp_line
			(start 0.32512 -0.175006)
			(end 0.32512 0.175006)
			(stroke
				(width 0.1)
				(type default)
			)
			(layer "F.Fab")
		)
		(pad "1" smd rect
			(at -0.2667 0 270)
			(size 0.3048 0.381)
			(layers "F.Cu" "F.Mask" "F.Paste")
			(net "USB3_CPU0_BMC_TX_C2_DN")
		)
		(pad "2" smd rect
			(at 0.2667 0 90)
			(size 0.3048 0.381)
			(layers "F.Cu" "F.Mask" "F.Paste")
			(net "GND")
		)
	)
)
